# S9S_MB_2U (Grand Teton) — schematic netlist excerpt (pin names and nets, part order shuffled) for the footprints in the layout excerpt that follows; sources: Cadence DE-HDL packaged netlist, KiCad conversion of 03242023_DA0F0TMBIJ0_F0T_Motherboard_J_brd_V01_OCP.brd

R4156  Q_RES  4.7K 5% CHIP  pkg 0402LF  page 146 : A = P3V3_AUX ; B = PRSNT_CABLE_GPU_A1_ISO_N
R4215  Q_RES  0 5% CHIP  pkg 0402LF  page 170 : A = FM_THERMAL_ALERT_N ; B = FM_G751_0_ALERT_N

(kicad_pcb
	(version 20260206)
	(generator "pcbnew")
	(generator_version "10.0")
	(general
		(thickness 1.6)
		(legacy_teardrops no)
	)
	(paper "A4")
	(title_block
		(title "03242023_DA0F0TMBIJ0_F0T_Motherboard_J_brd_V01_OCP.brd")
		(comment 1 "Grand Teton / footprints 3342-3343 of 6105")
	)
	(layers
		(0 "F.Cu" signal "TOP")
		(4 "In1.Cu" signal "GND")
		(6 "In2.Cu" signal "IN1")
		(8 "In3.Cu" signal "GND1")
		(10 "In4.Cu" signal "IN2")
		(12 "In5.Cu" signal "GND2")
		(14 "In6.Cu" signal "IN3")
		(16 "In7.Cu" signal "GND3")
		(18 "In8.Cu" signal "VCC")
		(20 "In9.Cu" signal "VCC1")
		(22 "In10.Cu" signal "GND4")
		(24 "In11.Cu" signal "IN4")
		(26 "In12.Cu" signal "GND5")
		(28 "In13.Cu" signal "IN5")
		(30 "In14.Cu" signal "GND6")
		(32 "In15.Cu" signal "IN6")
		(34 "In16.Cu" signal "GND7")
		(2 "B.Cu" signal "BOTTOM")
		(9 "F.Adhes" user "F.Adhesive")
		(11 "B.Adhes" user "B.Adhesive")
		(13 "F.Paste" user "Package Geometry/Pastemask Top")
		(15 "B.Paste" user "Package Geometry/Pastemask Bottom")
		(5 "F.SilkS" user "Ref Des/Silkscreen Top")
		(7 "B.SilkS" user "Ref Des/Silkscreen Bottom")
		(1 "F.Mask" user "Board Geometry/Soldermask Top")
		(3 "B.Mask" user "Board Geometry/Soldermask Bottom")
		(17 "Dwgs.User" user "User.Drawings")
		(19 "Cmts.User" user "User.Comments")
		(21 "Eco1.User" user "User.Eco1")
		(23 "Eco2.User" user "User.Eco2")
		(25 "Edge.Cuts" user "Board Geometry/Outline")
		(27 "Margin" user)
		(31 "F.CrtYd" user "Package Geometry/Place Bound Top")
		(29 "B.CrtYd" user "Package Geometry/Place Bound Bottom")
		(35 "F.Fab" user "Ref Des/Assembly Top")
		(33 "B.Fab" user "Ref Des/Assembly Bottom")
	)
	(footprint ""
		(layer "F.Cu")
		(at 295.86682 -421.41521 90)
		(property "Reference" "R4156"
			(at 0 0 90)
			(layer "F.SilkS")
			(hide yes)
			(effects
				(font
					(size 1.27 1.27)
				)
			)
		)
		(property "Value" ""
			(at 0 0 90)
			(layer "F.Fab")
			(effects
				(font
					(size 1.27 1.27)
				)
			)
		)
		(duplicate_pad_numbers_are_jumpers no)
		(fp_line
			(start 0.7874 -0.4064)
			(end 0.7874 0.4064)
			(stroke
				(width 0.1524)
				(type default)
			)
			(layer "F.SilkS")
		)
		(fp_line
			(start -0.7874 -0.4064)
			(end 0.7874 -0.4064)
			(stroke
				(width 0.1524)
				(type default)
			)
			(layer "F.SilkS")
		)
		(fp_line
			(start 0.7874 0.4064)
			(end -0.7874 0.4064)
			(stroke
				(width 0.1524)
				(type default)
			)
			(layer "F.SilkS")
		)
		(fp_line
			(start -0.7874 0.4064)
			(end -0.7874 -0.4064)
			(stroke
				(width 0.1524)
				(type default)
			)
			(layer "F.SilkS")
		)
		(fp_line
			(start -0.12065 -0.305054)
			(end -0.12065 -0.2794)
			(stroke
				(width 0.1)
				(type default)
			)
			(layer "F.Fab")
		)
		(fp_line
			(start -0.67945 -0.305054)
			(end -0.12065 -0.305054)
			(stroke
				(width 0.1)
				(type default)
			)
			(layer "F.Fab")
		)
		(fp_line
			(start 0.67945 -0.3048)
			(end 0.67945 0.3048)
			(stroke
				(width 0.1)
				(type default)
			)
			(layer "F.Fab")
		)
		(fp_line
			(start 0.12065 -0.3048)
			(end 0.67945 -0.3048)
			(stroke
				(width 0.1)
				(type default)
			)
			(layer "F.Fab")
		)
		(fp_line
			(start 0.12065 -0.2794)
			(end 0.12065 -0.3048)
			(stroke
				(width 0.1)
				(type default)
			)
			(layer "F.Fab")
		)
		(fp_line
			(start -0.12065 -0.2794)
			(end 0.12065 -0.2794)
			(stroke
				(width 0.1)
				(type default)
			)
			(layer "F.Fab")
		)
		(fp_line
			(start 0.120396 0.2794)
			(end -0.12065 0.2794)
			(stroke
				(width 0.1)
				(type default)
			)
			(layer "F.Fab")
		)
		(fp_line
			(start -0.12065 0.2794)
			(end -0.12065 0.3048)
			(stroke
				(width 0.1)
				(type default)
			)
			(layer "F.Fab")
		)
		(fp_line
			(start 0.67945 0.3048)
			(end 0.120396 0.3048)
			(stroke
				(width 0.1)
				(type default)
			)
			(layer "F.Fab")
		)
		(fp_line
			(start 0.120396 0.3048)
			(end 0.120396 0.2794)
			(stroke
				(width 0.1)
				(type default)
			)
			(layer "F.Fab")
		)
		(fp_line
			(start -0.12065 0.3048)
			(end -0.67945 0.3048)
			(stroke
				(width 0.1)
				(type default)
			)
			(layer "F.Fab")
		)
		(fp_line
			(start -0.67945 0.3048)
			(end -0.67945 -0.305054)
			(stroke
				(width 0.1)
				(type default)
			)
			(layer "F.Fab")
		)
		(pad "1" smd circle
			(at -0.40005 0 90)
			(size 0 0)
			(layers "F.Cu" "F.Mask" "F.Paste")
			(net "P3V3_AUX")
		)
		(pad "2" smd circle
			(at 0.40005 0 90)
			(size 0 0)
			(layers "F.Cu" "F.Mask" "F.Paste")
			(net "PRSNT_CABLE_GPU_A1_ISO_N")
		)
	)
	(footprint ""
		(layer "F.Cu")
		(at 366.454182 -423.03573)
		(property "Reference" "R4215"
			(at 0 0 0)
			(layer "F.SilkS")
			(hide yes)
			(effects
				(font
					(size 1.27 1.27)
				)
			)
		)
		(property "Value" ""
			(at 0 0 0)
			(layer "F.Fab")
			(effects
				(font
					(size 1.27 1.27)
				)
			)
		)
		(duplicate_pad_numbers_are_jumpers no)
		(fp_line
			(start -0.7874 -0.4064)
			(end 0.7874 -0.4064)
			(stroke
				(width 0.1524)
				(type default)
			)
			(layer "F.SilkS")
		)
		(fp_line
			(start -0.7874 0.4064)
			(end -0.7874 -0.4064)
			(stroke
				(width 0.1524)
				(type default)
			)
			(layer "F.SilkS")
		)
		(fp_line
			(start 0.7874 -0.4064)
			(end 0.7874 0.4064)
			(stroke
				(width 0.1524)
				(type default)
			)
			(layer "F.SilkS")
		)
		(fp_line
			(start 0.7874 0.4064)
			(end -0.7874 0.4064)
			(stroke
				(width 0.1524)
				(type default)
			)
			(layer "F.SilkS")
		)
		(fp_line
			(start -0.67945 -0.305054)
			(end -0.12065 -0.305054)
			(stroke
				(width 0.1)
				(type default)
			)
			(layer "F.Fab")
		)
		(fp_line
			(start -0.67945 0.3048)
			(end -0.67945 -0.305054)
			(stroke
				(width 0.1)
				(type default)
			)
			(layer "F.Fab")
		)
		(fp_line
			(start -0.12065 -0.305054)
			(end -0.12065 -0.2794)
			(stroke
				(width 0.1)
				(type default)
			)
			(layer "F.Fab")
		)
		(fp_line
			(start -0.12065 -0.2794)
			(end 0.12065 -0.2794)
			(stroke
				(width 0.1)
				(type default)
			)
			(layer "F.Fab")
		)
		(fp_line
			(start -0.12065 0.2794)
			(end -0.12065 0.3048)
			(stroke
				(width 0.1)
				(type default)
			)
			(layer "F.Fab")
		)
		(fp_line
			(start -0.12065 0.3048)
			(end -0.67945 0.3048)
			(stroke
				(width 0.1)
				(type default)
			)
			(layer "F.Fab")
		)
		(fp_line
			(start 0.120396 0.2794)
			(end -0.12065 0.2794)
			(stroke
				(width 0.1)
				(type default)
			)
			(layer "F.Fab")
		)
		(fp_line
			(start 0.120396 0.3048)
			(end 0.120396 0.2794)
			(stroke
				(width 0.1)
				(type default)
			)
			(layer "F.Fab")
		)
		(fp_line
			(start 0.12065 -0.3048)
			(end 0.67945 -0.3048)
			(stroke
				(width 0.1)
				(type default)
			)
			(layer "F.Fab")
		)
		(fp_line
			(start 0.12065 -0.2794)
			(end 0.12065 -0.3048)
			(stroke
				(width 0.1)
				(type default)
			)
			(layer "F.Fab")
		)
		(fp_line
			(start 0.67945 -0.3048)
			(end 0.67945 0.3048)
			(stroke
				(width 0.1)
				(type default)
			)
			(layer "F.Fab")
		)
		(fp_line
			(start 0.67945 0.3048)
			(end 0.120396 0.3048)
			(stroke
				(width 0.1)
				(type default)
			)
			(layer "F.Fab")
		)
		(pad "1" smd circle
			(at -0.40005 0)
			(size 0 0)
			(layers "F.Cu" "F.Mask" "F.Paste")
			(net "FM_THERMAL_ALERT_N")
		)
		(pad "2" smd circle
			(at 0.40005 0)
			(size 0 0)
			(layers "F.Cu" "F.Mask" "F.Paste")
			(net "FM_G751_0_ALERT_N")
		)
	)
)
